(kicad_pcb
	(version 20260206)
	(generator "pcbnew")
	(generator_version "10.0")
	(general
		(thickness 1.6)
		(legacy_teardrops no)
	)
	(paper "A4")
	(title_block
		(title "Bryce Canyon_F.DPB_16315-1-OCP.brd")
		(comment 1 "Bryce Canyon / footprints 362-367 of 2223")
	)
	(layers
		(0 "F.Cu" signal "TOP")
		(4 "In1.Cu" signal "L2GND")
		(6 "In2.Cu" signal "L3")
		(8 "In3.Cu" signal "L4GND")
		(10 "In4.Cu" signal "L5")
		(12 "In5.Cu" signal "L6VCC")
		(14 "In6.Cu" signal "L7VCC")
		(16 "In7.Cu" signal "L8")
		(18 "In8.Cu" signal "L9GND")
		(20 "In9.Cu" signal "L10")
		(22 "In10.Cu" signal "L11GND")
		(2 "B.Cu" signal "BOTTOM")
		(9 "F.Adhes" user "F.Adhesive")
		(11 "B.Adhes" user "B.Adhesive")
		(13 "F.Paste" user "Package Geometry/Pastemask Top")
		(15 "B.Paste" user "Package Geometry/Pastemask Bottom")
		(5 "F.SilkS" user "Ref Des/Silkscreen Top")
		(7 "B.SilkS" user "Ref Des/Silkscreen Bottom")
		(1 "F.Mask" user "Board Geometry/Soldermask Top")
		(3 "B.Mask" user "Board Geometry/Soldermask Bottom")
		(17 "Dwgs.User" user "User.Drawings")
		(19 "Cmts.User" user "User.Comments")
		(21 "Eco1.User" user "User.Eco1")
		(23 "Eco2.User" user "User.Eco2")
		(25 "Edge.Cuts" user "Board Geometry/Outline")
		(27 "Margin" user)
		(31 "F.CrtYd" user "Package Geometry/Place Bound Top")
		(29 "B.CrtYd" user "Package Geometry/Place Bound Bottom")
		(35 "F.Fab" user "Ref Des/Assembly Top")
		(33 "B.Fab" user "Ref Des/Assembly Bottom")
	)
	(footprint ""
		(layer "F.Cu")
		(at 337.291934 -21.45157 180)
		(property "Reference" "R99"
			(at 0 0 180)
			(layer "F.SilkS")
			(hide yes)
			(effects
				(font
					(size 1.27 1.27)
				)
			)
		)
		(property "Value" "4K7R2F-GP"
			(at 0.064008 -3.993896 180)
			(unlocked yes)
			(layer "F.Fab")
			(hide yes)
			(effects
				(font
					(size 1.016 1.016)
					(thickness 0.1524)
				)
			)
		)
		(property "Device Type" "R402H16"
			(at 0.064008 -5.517896 180)
			(unlocked yes)
			(layer "F.Fab")
			(hide yes)
			(effects
				(font
					(size 1.016 1.016)
					(thickness 0.1524)
				)
			)
		)
		(duplicate_pad_numbers_are_jumpers no)
		(fp_line
			(start 0.508 -0.9398)
			(end -0.508 -0.9398)
			(stroke
				(width 0.1524)
				(type default)
			)
			(layer "F.SilkS")
		)
		(fp_line
			(start -0.508 -0.9398)
			(end -0.508 0.9398)
			(stroke
				(width 0.1524)
				(type default)
			)
			(layer "F.SilkS")
		)
		(fp_rect
			(start -0.508 0.9398)
			(end 0.508 -0.9398)
			(stroke
				(width 0)
				(type default)
			)
			(fill no)
			(layer "F.CrtYd")
		)
		(fp_rect
			(start -0.508 0.9398)
			(end 0.508 -0.9398)
			(stroke
				(width 0)
				(type default)
			)
			(fill no)
			(layer "F.Fab")
		)
		(pad "1" smd custom
			(at 0 -0.4445 180)
			(size 0.1397 0.1397)
			(layers "F.Cu" "F.Mask" "F.Paste")
			(net "P3V3_STBY_B")
			(options
				(clearance outline)
				(anchor circle)
			)
			(primitives
				(gr_poly
					(pts
						(arc
							(start -0.1778 -0.2794)
							(mid -0.249642 -0.249642)
							(end -0.2794 -0.1778)
						)
						(arc
							(start -0.2794 0.1778)
							(mid -0.249642 0.249642)
							(end -0.1778 0.2794)
						)
						(arc
							(start 0.1778 0.2794)
							(mid 0.249642 0.249642)
							(end 0.2794 0.1778)
						)
						(arc
							(start 0.2794 -0.1778)
							(mid 0.249642 -0.249642)
							(end 0.1778 -0.2794)
						)
					)
					(width 0)
					(fill yes)
				)
			)
		)
		(pad "2" smd custom
			(at 0 0.4445 180)
			(size 0.1397 0.1397)
			(layers "F.Cu" "F.Mask" "F.Paste")
			(net "IO_EXP11_A2")
			(options
				(clearance outline)
				(anchor circle)
			)
			(primitives
				(gr_poly
					(pts
						(arc
							(start -0.1778 -0.2794)
							(mid -0.249642 -0.249642)
							(end -0.2794 -0.1778)
						)
						(arc
							(start -0.2794 0.1778)
							(mid -0.249642 0.249642)
							(end -0.1778 0.2794)
						)
						(arc
							(start 0.1778 0.2794)
							(mid 0.249642 0.249642)
							(end 0.2794 0.1778)
						)
						(arc
							(start 0.2794 -0.1778)
							(mid 0.249642 -0.249642)
							(end 0.1778 -0.2794)
						)
					)
					(width 0)
					(fill yes)
				)
			)
		)
	)
	(footprint ""
		(layer "F.Cu")
		(at 32.508952 -47.749968 -90)
		(property "Reference" "VIA58"
			(at 0 0 270)
			(layer "F.SilkS")
			(hide yes)
			(effects
				(font
					(size 1.27 1.27)
				)
			)
		)
		(property "Value" "100OHM-8L-1D6MM-L18L16-GP"
			(at -3.7211 -4.5085 270)
			(unlocked yes)
			(layer "F.Fab")
			(hide yes)
			(effects
				(font
					(size 1.016 1.016)
					(thickness 0.1524)
				)
			)
		)
		(property "Device Type" "VIA-PCIE-4P-394076"
			(at -3.7211 -6.0325 270)
			(unlocked yes)
			(layer "F.Fab")
			(hide yes)
			(effects
				(font
					(size 1.016 1.016)
					(thickness 0.1524)
				)
			)
		)
		(duplicate_pad_numbers_are_jumpers no)
		(fp_rect
			(start -1.9685 0.381)
			(end 1.9685 -0.381)
			(stroke
				(width 0)
				(type default)
			)
			(fill no)
			(layer "F.CrtYd")
		)
		(fp_rect
			(start -1.9685 0.381)
			(end 1.9685 -0.381)
			(stroke
				(width 0)
				(type default)
			)
			(fill no)
			(layer "F.Fab")
		)
		(pad "1" thru_hole circle
			(at -1.5875 0 270)
			(size 0.508 0.508)
			(drill 0.254)
			(layers "*.Cu" "*.Mask")
			(remove_unused_layers no)
			(net "GND")
			(clearance 0.127)
			(thermal_gap 0.127)
		)
		(pad "2" thru_hole circle
			(at -0.5715 0 270)
			(size 0.508 0.508)
			(drill 0.254)
			(layers "*.Cu" "*.Mask")
			(remove_unused_layers no)
			(net "PHY_DRV_A_TO_SCC_A_24_DP")
			(clearance 0.127)
			(thermal_gap 0.127)
		)
		(pad "3" thru_hole circle
			(at 0.5715 0 270)
			(size 0.508 0.508)
			(drill 0.254)
			(layers "*.Cu" "*.Mask")
			(remove_unused_layers no)
			(net "PHY_DRV_A_TO_SCC_A_24_DN")
			(clearance 0.127)
			(thermal_gap 0.127)
		)
		(pad "4" thru_hole circle
			(at 1.5875 0 270)
			(size 0.508 0.508)
			(drill 0.254)
			(layers "*.Cu" "*.Mask")
			(remove_unused_layers no)
			(net "GND")
			(clearance 0.127)
			(thermal_gap 0.127)
		)
	)
	(footprint ""
		(layer "F.Cu")
		(at 259.300472 10.1854 90)
		(property "Reference" "R610"
			(at 0 0 90)
			(layer "F.SilkS")
			(hide yes)
			(effects
				(font
					(size 1.27 1.27)
				)
			)
		)
		(property "Value" "10KR2F-2-GP"
			(at 0.064008 -3.993896 90)
			(unlocked yes)
			(layer "F.Fab")
			(hide yes)
			(effects
				(font
					(size 1.016 1.016)
					(thickness 0.1524)
				)
			)
		)
		(property "Device Type" "R402H16"
			(at 0.064008 -5.517896 90)
			(unlocked yes)
			(layer "F.Fab")
			(hide yes)
			(effects
				(font
					(size 1.016 1.016)
					(thickness 0.1524)
				)
			)
		)
		(duplicate_pad_numbers_are_jumpers no)
		(fp_line
			(start 0.508 -0.9398)
			(end -0.508 -0.9398)
			(stroke
				(width 0.1524)
				(type default)
			)
			(layer "F.SilkS")
		)
		(fp_line
			(start -0.508 -0.9398)
			(end -0.508 0.9398)
			(stroke
				(width 0.1524)
				(type default)
			)
			(layer "F.SilkS")
		)
		(fp_rect
			(start -0.508 0.9398)
			(end 0.508 -0.9398)
			(stroke
				(width 0)
				(type default)
			)
			(fill no)
			(layer "F.CrtYd")
		)
		(fp_rect
			(start -0.508 0.9398)
			(end 0.508 -0.9398)
			(stroke
				(width 0)
				(type default)
			)
			(fill no)
			(layer "F.Fab")
		)
		(pad "1" smd custom
			(at 0 -0.4445 90)
			(size 0.1397 0.1397)
			(layers "F.Cu" "F.Mask" "F.Paste")
			(net "IOM_A_FAULT_LED")
			(options
				(clearance outline)
				(anchor circle)
			)
			(primitives
				(gr_poly
					(pts
						(arc
							(start -0.1778 -0.2794)
							(mid -0.249642 -0.249642)
							(end -0.2794 -0.1778)
						)
						(arc
							(start -0.2794 0.1778)
							(mid -0.249642 0.249642)
							(end -0.1778 0.2794)
						)
						(arc
							(start 0.1778 0.2794)
							(mid 0.249642 0.249642)
							(end 0.2794 0.1778)
						)
						(arc
							(start 0.2794 -0.1778)
							(mid 0.249642 -0.249642)
							(end 0.1778 -0.2794)
						)
					)
					(width 0)
					(fill yes)
				)
			)
		)
		(pad "2" smd custom
			(at 0 0.4445 90)
			(size 0.1397 0.1397)
			(layers "F.Cu" "F.Mask" "F.Paste")
			(net "GND")
			(options
				(clearance outline)
				(anchor circle)
			)
			(primitives
				(gr_poly
					(pts
						(arc
							(start -0.1778 -0.2794)
							(mid -0.249642 -0.249642)
							(end -0.2794 -0.1778)
						)
						(arc
							(start -0.2794 0.1778)
							(mid -0.249642 0.249642)
							(end -0.1778 0.2794)
						)
						(arc
							(start 0.1778 0.2794)
							(mid 0.249642 0.249642)
							(end 0.2794 0.1778)
						)
						(arc
							(start 0.2794 -0.1778)
							(mid 0.249642 -0.249642)
							(end 0.1778 -0.2794)
						)
					)
					(width 0)
					(fill yes)
				)
			)
		)
	)
	(footprint ""
		(layer "F.Cu")
		(at 175.848518 -28.635452 90)
		(property "Reference" "C81"
			(at 0 0 90)
			(layer "F.SilkS")
			(hide yes)
			(effects
				(font
					(size 1.27 1.27)
				)
			)
		)
		(property "Value" "SCD1U16V2KX-3GP"
			(at 1.1811 -2.7051 90)
			(unlocked yes)
			(layer "F.Fab")
			(hide yes)
			(effects
				(font
					(size 1.016 1.016)
					(thickness 0.1524)
				)
			)
		)
		(property "Device Type" "C402H22"
			(at 1.1811 -4.2291 90)
			(unlocked yes)
			(layer "F.Fab")
			(hide yes)
			(effects
				(font
					(size 1.016 1.016)
					(thickness 0.1524)
				)
			)
		)
		(duplicate_pad_numbers_are_jumpers no)
		(fp_rect
			(start -0.4318 0.9525)
			(end 0.4318 -0.9525)
			(stroke
				(width 0)
				(type default)
			)
			(fill no)
			(layer "F.CrtYd")
		)
		(fp_rect
			(start -0.4318 0.9525)
			(end 0.4318 -0.9525)
			(stroke
				(width 0)
				(type default)
			)
			(fill no)
			(layer "F.Fab")
		)
		(pad "1" smd custom
			(at 0 -0.4445 90)
			(size 0.1524 0.1524)
			(layers "F.Cu" "F.Mask" "F.Paste")
			(net "P3V3_STBY_A")
			(options
				(clearance outline)
				(anchor circle)
			)
			(primitives
				(gr_poly
					(pts
						(arc
							(start 0.3048 -0.2032)
							(mid 0.275042 -0.275042)
							(end 0.2032 -0.3048)
						)
						(arc
							(start -0.2032 -0.3048)
							(mid -0.275042 -0.275042)
							(end -0.3048 -0.2032)
						)
						(arc
							(start -0.3048 0.2032)
							(mid -0.275042 0.275042)
							(end -0.2032 0.3048)
						)
						(arc
							(start 0.2032 0.3048)
							(mid 0.275042 0.275042)
							(end 0.3048 0.2032)
						)
					)
					(width 0)
					(fill yes)
				)
			)
		)
		(pad "2" smd custom
			(at 0 0.4445 90)
			(size 0.1524 0.1524)
			(layers "F.Cu" "F.Mask" "F.Paste")
			(net "GND")
			(options
				(clearance outline)
				(anchor circle)
			)
			(primitives
				(gr_poly
					(pts
						(arc
							(start 0.3048 -0.2032)
							(mid 0.275042 -0.275042)
							(end 0.2032 -0.3048)
						)
						(arc
							(start -0.2032 -0.3048)
							(mid -0.275042 -0.275042)
							(end -0.3048 -0.2032)
						)
						(arc
							(start -0.3048 0.2032)
							(mid -0.275042 0.275042)
							(end -0.2032 0.3048)
						)
						(arc
							(start 0.2032 0.3048)
							(mid 0.275042 0.275042)
							(end 0.3048 0.2032)
						)
					)
					(width 0)
					(fill yes)
				)
			)
		)
	)
	(footprint ""
		(layer "F.Cu")
		(at 263.81837 -29.811726)
		(property "Reference" "TC18"
			(at 0 0 0)
			(layer "F.SilkS")
			(hide yes)
			(effects
				(font
					(size 1.27 1.27)
				)
			)
		)
		(property "Value" "SE270U16VM-8-GP"
			(at -4.5974 -2.54 0)
			(unlocked yes)
			(layer "F.Fab")
			(hide yes)
			(effects
				(font
					(size 1.016 1.016)
					(thickness 0.1524)
				)
			)
		)
		(property "Device Type" "SE361416H394"
			(at -4.5974 -4.064 0)
			(unlocked yes)
			(layer "F.Fab")
			(hide yes)
			(effects
				(font
					(size 1.016 1.016)
					(thickness 0.1524)
				)
			)
		)
		(duplicate_pad_numbers_are_jumpers no)
		(fp_line
			(start -3.556 -3.4163)
			(end -2.3622 -4.6101)
			(stroke
				(width 0.1524)
				(type default)
			)
			(layer "F.SilkS")
		)
		(fp_line
			(start -3.556 4.6101)
			(end -3.556 -3.4163)
			(stroke
				(width 0.1524)
				(type default)
			)
			(layer "F.SilkS")
		)
		(fp_line
			(start -2.3622 -4.6101)
			(end 2.3622 -4.6101)
			(stroke
				(width 0.1524)
				(type default)
			)
			(layer "F.SilkS")
		)
		(fp_line
			(start 2.3622 -4.6101)
			(end 3.556 -3.4163)
			(stroke
				(width 0.1524)
				(type default)
			)
			(layer "F.SilkS")
		)
		(fp_line
			(start 3.556 -3.4163)
			(end 3.556 4.6101)
			(stroke
				(width 0.1524)
				(type default)
			)
			(layer "F.SilkS")
		)
		(fp_line
			(start 3.556 4.6101)
			(end -3.556 4.6101)
			(stroke
				(width 0.1524)
				(type default)
			)
			(layer "F.SilkS")
		)
		(fp_rect
			(start -3.302 3.6449)
			(end 3.302 -3.6449)
			(stroke
				(width 0)
				(type default)
			)
			(fill no)
			(layer "F.CrtYd")
		)
		(fp_poly
			(pts
				(xy 3.81 4.6863) (xy 3.81 -3.4925) (xy 3.302 -3.4925) (xy 3.302 3.6449) (xy -3.302 3.6449) (xy -3.302 -3.6449)
				(xy 3.302 -3.6449) (xy 3.302 -3.5052) (xy 3.81 -3.5052) (xy 3.81 -4.6863) (xy -3.81 -4.6863) (xy -3.81 4.6863)
			)
			(stroke
				(width 0)
				(type default)
			)
			(fill no)
			(layer "F.CrtYd")
		)
		(fp_rect
			(start -3.81 4.6863)
			(end 3.81 -4.6863)
			(stroke
				(width 0)
				(type default)
			)
			(fill no)
			(layer "F.Fab")
		)
		(pad "1" smd rect
			(at 0 -2.574036)
			(size 1.4224 3.556)
			(layers "F.Cu" "F.Mask" "F.Paste")
			(net "P12V_A")
		)
		(pad "2" smd rect
			(at 0 2.574036)
			(size 1.4224 3.556)
			(layers "F.Cu" "F.Mask" "F.Paste")
			(net "GND")
		)
	)
	(footprint ""
		(layer "F.Cu")
		(at 118.890796 -74.462894 180)
		(property "Reference" "C398"
			(at 0 0 180)
			(layer "F.SilkS")
			(hide yes)
			(effects
				(font
					(size 1.27 1.27)
				)
			)
		)
		(property "Value" "SC1U25V3KX-GP"
			(at 0 -2.8194 180)
			(unlocked yes)
			(layer "F.Fab")
			(hide yes)
			(effects
				(font
					(size 1.016 1.016)
					(thickness 0.1524)
				)
			)
		)
		(property "Device Type" "C603H36"
			(at 0 -4.3434 180)
			(unlocked yes)
			(layer "F.Fab")
			(hide yes)
			(effects
				(font
					(size 1.016 1.016)
					(thickness 0.1524)
				)
			)
		)
		(duplicate_pad_numbers_are_jumpers no)
		(fp_line
			(start 0.508 0)
			(end -0.508 0)
			(stroke
				(width 0.2032)
				(type default)
			)
			(layer "F.SilkS")
		)
		(fp_rect
			(start -0.5842 1.3335)
			(end 0.5842 -1.3335)
			(stroke
				(width 0)
				(type default)
			)
			(fill no)
			(layer "F.CrtYd")
		)
		(fp_rect
			(start -0.5842 1.3335)
			(end 0.5842 -1.3335)
			(stroke
				(width 0)
				(type default)
			)
			(fill no)
			(layer "F.Fab")
		)
		(pad "1" smd custom
			(at 0 -0.762 180)
			(size 0.2159 0.2159)
			(layers "F.Cu" "F.Mask" "F.Paste")
			(net "P12V_HDD27")
			(options
				(clearance outline)
				(anchor circle)
			)
			(primitives
				(gr_poly
					(pts
						(arc
							(start -0.3302 -0.4318)
							(mid -0.402042 -0.402042)
							(end -0.4318 -0.3302)
						)
						(arc
							(start -0.4318 0.3302)
							(mid -0.402042 0.402042)
							(end -0.3302 0.4318)
						)
						(arc
							(start 0.3302 0.4318)
							(mid 0.402042 0.402042)
							(end 0.4318 0.3302)
						)
						(arc
							(start 0.4318 -0.3302)
							(mid 0.402042 -0.402042)
							(end 0.3302 -0.4318)
						)
					)
					(width 0)
					(fill yes)
				)
			)
		)
		(pad "2" smd custom
			(at 0 0.762 180)
			(size 0.2159 0.2159)
			(layers "F.Cu" "F.Mask" "F.Paste")
			(net "GND")
			(options
				(clearance outline)
				(anchor circle)
			)
			(primitives
				(gr_poly
					(pts
						(arc
							(start -0.3302 -0.4318)
							(mid -0.402042 -0.402042)
							(end -0.4318 -0.3302)
						)
						(arc
							(start -0.4318 0.3302)
							(mid -0.402042 0.402042)
							(end -0.3302 0.4318)
						)
						(arc
							(start 0.3302 0.4318)
							(mid 0.402042 0.402042)
							(end 0.4318 0.3302)
						)
						(arc
							(start 0.4318 -0.3302)
							(mid 0.402042 -0.402042)
							(end 0.3302 -0.4318)
						)
					)
					(width 0)
					(fill yes)
				)
			)
		)
	)
)
